(kicad_pcb
	(version 20260206)
	(generator "pcbnew")
	(generator_version "10.0")
	(general
		(thickness 1.6)
		(legacy_teardrops no)
	)
	(paper "A4")
	(title_block
		(title "01162023_DA0F0TEBIF0_F0T_Expander_BD_F_brd_V02_OCP.brd")
		(comment 1 "Grand Teton / footprints 7831-7837 of 9728")
	)
	(layers
		(0 "F.Cu" signal "TOP")
		(4 "In1.Cu" signal "GND")
		(6 "In2.Cu" signal "VCC")
		(8 "In3.Cu" signal "VCC1")
		(10 "In4.Cu" signal "GND1")
		(12 "In5.Cu" signal "IN1")
		(14 "In6.Cu" signal "GND2")
		(16 "In7.Cu" signal "IN2")
		(18 "In8.Cu" signal "GND3")
		(20 "In9.Cu" signal "IN3")
		(22 "In10.Cu" signal "GND4")
		(24 "In11.Cu" signal "IN4")
		(26 "In12.Cu" signal "GND5")
		(28 "In13.Cu" signal "IN5")
		(30 "In14.Cu" signal "GND6")
		(32 "In15.Cu" signal "IN6")
		(34 "In16.Cu" signal "GND7")
		(2 "B.Cu" signal "BOTTOM")
		(9 "F.Adhes" user "F.Adhesive")
		(11 "B.Adhes" user "B.Adhesive")
		(13 "F.Paste" user "Package Geometry/Pastemask Top")
		(15 "B.Paste" user "Package Geometry/Pastemask Bottom")
		(5 "F.SilkS" user "Ref Des/Silkscreen Top")
		(7 "B.SilkS" user "Ref Des/Silkscreen Bottom")
		(1 "F.Mask" user "Board Geometry/Soldermask Top")
		(3 "B.Mask" user "Board Geometry/Soldermask Bottom")
		(17 "Dwgs.User" user "User.Drawings")
		(19 "Cmts.User" user "User.Comments")
		(21 "Eco1.User" user "User.Eco1")
		(23 "Eco2.User" user "User.Eco2")
		(25 "Edge.Cuts" user "Board Geometry/Outline")
		(27 "Margin" user)
		(31 "F.CrtYd" user "Package Geometry/Place Bound Top")
		(29 "B.CrtYd" user "Package Geometry/Place Bound Bottom")
		(35 "F.Fab" user "Ref Des/Assembly Top")
		(33 "B.Fab" user "Ref Des/Assembly Bottom")
	)
	(footprint ""
		(layer "B.Cu")
		(at 112.85728 -313.620404 180)
		(property "Reference" "R5784"
			(at 0 0 0)
			(layer "B.SilkS")
			(hide yes)
			(effects
				(font
					(size 1.27 1.27)
				)
				(justify mirror)
			)
		)
		(property "Value" ""
			(at 0 0 0)
			(layer "B.Fab")
			(effects
				(font
					(size 1.27 1.27)
				)
				(justify mirror)
			)
		)
		(duplicate_pad_numbers_are_jumpers no)
		(fp_line
			(start 2.576322 1.1303)
			(end 2.576322 -1.1303)
			(stroke
				(width 0.1524)
				(type default)
			)
			(layer "B.SilkS")
		)
		(fp_line
			(start 2.576322 -1.1303)
			(end -2.576322 -1.1303)
			(stroke
				(width 0.1524)
				(type default)
			)
			(layer "B.SilkS")
		)
		(fp_line
			(start -2.576322 1.1303)
			(end 2.576322 1.1303)
			(stroke
				(width 0.1524)
				(type default)
			)
			(layer "B.SilkS")
		)
		(fp_line
			(start -2.576322 -1.1303)
			(end -2.576322 1.1303)
			(stroke
				(width 0.1524)
				(type default)
			)
			(layer "B.SilkS")
		)
		(fp_line
			(start 1.649984 0.899922)
			(end -1.649984 0.899922)
			(stroke
				(width 0.1)
				(type default)
			)
			(layer "B.Fab")
		)
		(fp_line
			(start 1.649984 -0.899922)
			(end 1.649984 0.899922)
			(stroke
				(width 0.1)
				(type default)
			)
			(layer "B.Fab")
		)
		(fp_line
			(start -1.649984 0.899922)
			(end -1.649984 -0.899922)
			(stroke
				(width 0.1)
				(type default)
			)
			(layer "B.Fab")
		)
		(fp_line
			(start -1.649984 -0.899922)
			(end 1.649984 -0.899922)
			(stroke
				(width 0.1)
				(type default)
			)
			(layer "B.Fab")
		)
		(pad "1A" smd rect
			(at 1.700022 0)
			(size 1.4986 2.0066)
			(layers "B.Cu" "B.Mask" "B.Paste")
			(net "P0V8_PEX0")
		)
		(pad "1B" smd rect
			(at 1.077722 0)
			(size 0.254 0.508)
			(layers "B.Cu" "B.Mask" "B.Paste")
			(net "P0V8_PEX0")
		)
		(pad "2A" smd rect
			(at -1.700022 0)
			(size 1.4986 2.0066)
			(layers "B.Cu" "B.Mask" "B.Paste")
			(net "P0V8_SERDES_VDDA_PEX0")
		)
		(pad "2B" smd rect
			(at -1.077722 0)
			(size 0.254 0.508)
			(layers "B.Cu" "B.Mask" "B.Paste")
			(net "P0V8_SERDES_VDDA_PEX0")
		)
	)
	(footprint ""
		(layer "B.Cu")
		(at 275.163788 -285.853632)
		(property "Reference" "C3338"
			(at 0 0 0)
			(layer "B.SilkS")
			(hide yes)
			(effects
				(font
					(size 1.27 1.27)
				)
				(justify mirror)
			)
		)
		(property "Value" ""
			(at 0 0 0)
			(layer "B.Fab")
			(effects
				(font
					(size 1.27 1.27)
				)
				(justify mirror)
			)
		)
		(duplicate_pad_numbers_are_jumpers no)
		(fp_line
			(start -1.2954 -0.5842)
			(end -1.2954 0.5842)
			(stroke
				(width 0.1524)
				(type default)
			)
			(layer "B.SilkS")
		)
		(fp_line
			(start -1.2954 0.5842)
			(end 1.2954 0.5842)
			(stroke
				(width 0.1524)
				(type default)
			)
			(layer "B.SilkS")
		)
		(fp_line
			(start 1.2954 -0.5842)
			(end -1.2954 -0.5842)
			(stroke
				(width 0.1524)
				(type default)
			)
			(layer "B.SilkS")
		)
		(fp_line
			(start 1.2954 0.5842)
			(end 1.2954 -0.5842)
			(stroke
				(width 0.1524)
				(type default)
			)
			(layer "B.SilkS")
		)
		(fp_line
			(start -1.1938 -0.4064)
			(end -1.1938 0.4064)
			(stroke
				(width 0.1)
				(type default)
			)
			(layer "B.Fab")
		)
		(fp_line
			(start -1.1938 0.4064)
			(end -0.8636 0.4064)
			(stroke
				(width 0.1)
				(type default)
			)
			(layer "B.Fab")
		)
		(fp_line
			(start -0.8636 -0.4572)
			(end -0.8636 -0.4064)
			(stroke
				(width 0.1)
				(type default)
			)
			(layer "B.Fab")
		)
		(fp_line
			(start -0.8636 -0.4064)
			(end -1.1938 -0.4064)
			(stroke
				(width 0.1)
				(type default)
			)
			(layer "B.Fab")
		)
		(fp_line
			(start -0.8636 0.4064)
			(end -0.8636 0.4572)
			(stroke
				(width 0.1)
				(type default)
			)
			(layer "B.Fab")
		)
		(fp_line
			(start -0.8636 0.4572)
			(end 0.8636 0.4572)
			(stroke
				(width 0.1)
				(type default)
			)
			(layer "B.Fab")
		)
		(fp_line
			(start 0.8636 -0.4572)
			(end -0.8636 -0.4572)
			(stroke
				(width 0.1)
				(type default)
			)
			(layer "B.Fab")
		)
		(fp_line
			(start 0.8636 -0.4064)
			(end 0.8636 -0.4572)
			(stroke
				(width 0.1)
				(type default)
			)
			(layer "B.Fab")
		)
		(fp_line
			(start 0.8636 0.4064)
			(end 1.1938 0.4064)
			(stroke
				(width 0.1)
				(type default)
			)
			(layer "B.Fab")
		)
		(fp_line
			(start 0.8636 0.4572)
			(end 0.8636 0.4064)
			(stroke
				(width 0.1)
				(type default)
			)
			(layer "B.Fab")
		)
		(fp_line
			(start 1.1938 -0.4064)
			(end 0.8636 -0.4064)
			(stroke
				(width 0.1)
				(type default)
			)
			(layer "B.Fab")
		)
		(fp_line
			(start 1.1938 0.4064)
			(end 1.1938 -0.4064)
			(stroke
				(width 0.1)
				(type default)
			)
			(layer "B.Fab")
		)
		(pad "1" smd rect
			(at 0.7366 0 270)
			(size 0.7112 0.8128)
			(layers "B.Cu" "B.Mask" "B.Paste")
			(net "P1V8_PEX")
		)
		(pad "2" smd rect
			(at -0.7366 0 270)
			(size 0.7112 0.8128)
			(layers "B.Cu" "B.Mask" "B.Paste")
			(net "GND")
		)
	)
	(footprint ""
		(layer "B.Cu")
		(at 233.498644 -231.225598 -90)
		(property "Reference" "R4516"
			(at 0 0 90)
			(layer "B.SilkS")
			(hide yes)
			(effects
				(font
					(size 1.27 1.27)
				)
				(justify mirror)
			)
		)
		(property "Value" ""
			(at 0 0 90)
			(layer "B.Fab")
			(effects
				(font
					(size 1.27 1.27)
				)
				(justify mirror)
			)
		)
		(duplicate_pad_numbers_are_jumpers no)
		(fp_line
			(start -0.7874 0.4064)
			(end 0.7874 0.4064)
			(stroke
				(width 0.1524)
				(type default)
			)
			(layer "B.SilkS")
		)
		(fp_line
			(start 0.7874 0.4064)
			(end 0.7874 -0.4064)
			(stroke
				(width 0.1524)
				(type default)
			)
			(layer "B.SilkS")
		)
		(fp_line
			(start -0.7874 -0.4064)
			(end -0.7874 0.4064)
			(stroke
				(width 0.1524)
				(type default)
			)
			(layer "B.SilkS")
		)
		(fp_line
			(start 0.7874 -0.4064)
			(end -0.7874 -0.4064)
			(stroke
				(width 0.1524)
				(type default)
			)
			(layer "B.SilkS")
		)
		(fp_line
			(start -0.67945 0.3048)
			(end -0.120396 0.3048)
			(stroke
				(width 0.1)
				(type default)
			)
			(layer "B.Fab")
		)
		(fp_line
			(start -0.120396 0.3048)
			(end -0.120396 0.2794)
			(stroke
				(width 0.1)
				(type default)
			)
			(layer "B.Fab")
		)
		(fp_line
			(start 0.12065 0.3048)
			(end 0.67945 0.3048)
			(stroke
				(width 0.1)
				(type default)
			)
			(layer "B.Fab")
		)
		(fp_line
			(start 0.67945 0.3048)
			(end 0.67945 -0.305054)
			(stroke
				(width 0.1)
				(type default)
			)
			(layer "B.Fab")
		)
		(fp_line
			(start -0.120396 0.2794)
			(end 0.12065 0.2794)
			(stroke
				(width 0.1)
				(type default)
			)
			(layer "B.Fab")
		)
		(fp_line
			(start 0.12065 0.2794)
			(end 0.12065 0.3048)
			(stroke
				(width 0.1)
				(type default)
			)
			(layer "B.Fab")
		)
		(fp_line
			(start -0.12065 -0.2794)
			(end -0.12065 -0.3048)
			(stroke
				(width 0.1)
				(type default)
			)
			(layer "B.Fab")
		)
		(fp_line
			(start 0.12065 -0.2794)
			(end -0.12065 -0.2794)
			(stroke
				(width 0.1)
				(type default)
			)
			(layer "B.Fab")
		)
		(fp_line
			(start -0.67945 -0.3048)
			(end -0.67945 0.3048)
			(stroke
				(width 0.1)
				(type default)
			)
			(layer "B.Fab")
		)
		(fp_line
			(start -0.12065 -0.3048)
			(end -0.67945 -0.3048)
			(stroke
				(width 0.1)
				(type default)
			)
			(layer "B.Fab")
		)
		(fp_line
			(start 0.12065 -0.305054)
			(end 0.12065 -0.2794)
			(stroke
				(width 0.1)
				(type default)
			)
			(layer "B.Fab")
		)
		(fp_line
			(start 0.67945 -0.305054)
			(end 0.12065 -0.305054)
			(stroke
				(width 0.1)
				(type default)
			)
			(layer "B.Fab")
		)
		(pad "1" smd circle
			(at 0.40005 0 90)
			(size 0 0)
			(layers "B.Cu" "B.Mask" "B.Paste")
			(net "SSD2_PWRDIS_BIC")
		)
		(pad "2" smd circle
			(at -0.40005 0 90)
			(size 0 0)
			(layers "B.Cu" "B.Mask" "B.Paste")
			(net "SSD2_PWRDIS_BIC_R")
		)
	)
	(footprint ""
		(layer "B.Cu")
		(at 306.226718 -301.124874 -90)
		(property "Reference" "R1380"
			(at 0 0 90)
			(layer "B.SilkS")
			(hide yes)
			(effects
				(font
					(size 1.27 1.27)
				)
				(justify mirror)
			)
		)
		(property "Value" ""
			(at 0 0 90)
			(layer "B.Fab")
			(effects
				(font
					(size 1.27 1.27)
				)
				(justify mirror)
			)
		)
		(duplicate_pad_numbers_are_jumpers no)
		(fp_line
			(start -0.7874 0.4064)
			(end 0.7874 0.4064)
			(stroke
				(width 0.1524)
				(type default)
			)
			(layer "B.SilkS")
		)
		(fp_line
			(start 0.7874 0.4064)
			(end 0.7874 -0.4064)
			(stroke
				(width 0.1524)
				(type default)
			)
			(layer "B.SilkS")
		)
		(fp_line
			(start -0.7874 -0.4064)
			(end -0.7874 0.4064)
			(stroke
				(width 0.1524)
				(type default)
			)
			(layer "B.SilkS")
		)
		(fp_line
			(start 0.7874 -0.4064)
			(end -0.7874 -0.4064)
			(stroke
				(width 0.1524)
				(type default)
			)
			(layer "B.SilkS")
		)
		(fp_line
			(start -0.67945 0.3048)
			(end -0.120396 0.3048)
			(stroke
				(width 0.1)
				(type default)
			)
			(layer "B.Fab")
		)
		(fp_line
			(start -0.120396 0.3048)
			(end -0.120396 0.2794)
			(stroke
				(width 0.1)
				(type default)
			)
			(layer "B.Fab")
		)
		(fp_line
			(start 0.12065 0.3048)
			(end 0.67945 0.3048)
			(stroke
				(width 0.1)
				(type default)
			)
			(layer "B.Fab")
		)
		(fp_line
			(start 0.67945 0.3048)
			(end 0.67945 -0.305054)
			(stroke
				(width 0.1)
				(type default)
			)
			(layer "B.Fab")
		)
		(fp_line
			(start -0.120396 0.2794)
			(end 0.12065 0.2794)
			(stroke
				(width 0.1)
				(type default)
			)
			(layer "B.Fab")
		)
		(fp_line
			(start 0.12065 0.2794)
			(end 0.12065 0.3048)
			(stroke
				(width 0.1)
				(type default)
			)
			(layer "B.Fab")
		)
		(fp_line
			(start -0.12065 -0.2794)
			(end -0.12065 -0.3048)
			(stroke
				(width 0.1)
				(type default)
			)
			(layer "B.Fab")
		)
		(fp_line
			(start 0.12065 -0.2794)
			(end -0.12065 -0.2794)
			(stroke
				(width 0.1)
				(type default)
			)
			(layer "B.Fab")
		)
		(fp_line
			(start -0.67945 -0.3048)
			(end -0.67945 0.3048)
			(stroke
				(width 0.1)
				(type default)
			)
			(layer "B.Fab")
		)
		(fp_line
			(start -0.12065 -0.3048)
			(end -0.67945 -0.3048)
			(stroke
				(width 0.1)
				(type default)
			)
			(layer "B.Fab")
		)
		(fp_line
			(start 0.12065 -0.305054)
			(end 0.12065 -0.2794)
			(stroke
				(width 0.1)
				(type default)
			)
			(layer "B.Fab")
		)
		(fp_line
			(start 0.67945 -0.305054)
			(end 0.12065 -0.305054)
			(stroke
				(width 0.1)
				(type default)
			)
			(layer "B.Fab")
		)
		(pad "1" smd circle
			(at 0.40005 0 90)
			(size 0 0)
			(layers "B.Cu" "B.Mask" "B.Paste")
			(net "PEX2_ADCTEMP_VINP0")
		)
		(pad "2" smd circle
			(at -0.40005 0 90)
			(size 0 0)
			(layers "B.Cu" "B.Mask" "B.Paste")
			(net "GND")
		)
	)
	(footprint ""
		(layer "B.Cu")
		(at 286.149796 -290.199826 90)
		(property "Reference" "C1730"
			(at 0 0 90)
			(layer "B.SilkS")
			(hide yes)
			(effects
				(font
					(size 1.27 1.27)
				)
				(justify mirror)
			)
		)
		(property "Value" ""
			(at 0 0 90)
			(layer "B.Fab")
			(effects
				(font
					(size 1.27 1.27)
				)
				(justify mirror)
			)
		)
		(duplicate_pad_numbers_are_jumpers no)
		(fp_line
			(start 0.299974 -0.150114)
			(end -0.299974 -0.150114)
			(stroke
				(width 0.1)
				(type default)
			)
			(layer "B.Fab")
		)
		(fp_line
			(start -0.299974 -0.150114)
			(end -0.299974 0.150114)
			(stroke
				(width 0.1)
				(type default)
			)
			(layer "B.Fab")
		)
		(fp_line
			(start 0.299974 0.150114)
			(end 0.299974 -0.150114)
			(stroke
				(width 0.1)
				(type default)
			)
			(layer "B.Fab")
		)
		(fp_line
			(start -0.299974 0.150114)
			(end 0.299974 0.150114)
			(stroke
				(width 0.1)
				(type default)
			)
			(layer "B.Fab")
		)
		(pad "1" smd rect
			(at 0.2667 0 270)
			(size 0.3048 0.381)
			(layers "B.Cu" "B.Mask" "B.Paste")
			(net "P0V8_SERDES_VDDA_PEX2")
		)
		(pad "2" smd rect
			(at -0.2667 0 270)
			(size 0.3048 0.381)
			(layers "B.Cu" "B.Mask" "B.Paste")
			(net "GND")
		)
	)
	(footprint ""
		(layer "B.Cu")
		(at 322.360798 -83.123278 180)
		(property "Reference" "R1780"
			(at 0 0 0)
			(layer "B.SilkS")
			(hide yes)
			(effects
				(font
					(size 1.27 1.27)
				)
				(justify mirror)
			)
		)
		(property "Value" ""
			(at 0 0 0)
			(layer "B.Fab")
			(effects
				(font
					(size 1.27 1.27)
				)
				(justify mirror)
			)
		)
		(duplicate_pad_numbers_are_jumpers no)
		(fp_line
			(start 0.7874 0.4064)
			(end 0.7874 -0.4064)
			(stroke
				(width 0.1524)
				(type default)
			)
			(layer "B.SilkS")
		)
		(fp_line
			(start 0.7874 -0.4064)
			(end -0.7874 -0.4064)
			(stroke
				(width 0.1524)
				(type default)
			)
			(layer "B.SilkS")
		)
		(fp_line
			(start -0.7874 0.4064)
			(end 0.7874 0.4064)
			(stroke
				(width 0.1524)
				(type default)
			)
			(layer "B.SilkS")
		)
		(fp_line
			(start -0.7874 -0.4064)
			(end -0.7874 0.4064)
			(stroke
				(width 0.1524)
				(type default)
			)
			(layer "B.SilkS")
		)
		(fp_line
			(start 0.67945 0.3048)
			(end 0.67945 -0.305054)
			(stroke
				(width 0.1)
				(type default)
			)
			(layer "B.Fab")
		)
		(fp_line
			(start 0.67945 -0.305054)
			(end 0.12065 -0.305054)
			(stroke
				(width 0.1)
				(type default)
			)
			(layer "B.Fab")
		)
		(fp_line
			(start 0.12065 0.3048)
			(end 0.67945 0.3048)
			(stroke
				(width 0.1)
				(type default)
			)
			(layer "B.Fab")
		)
		(fp_line
			(start 0.12065 0.2794)
			(end 0.12065 0.3048)
			(stroke
				(width 0.1)
				(type default)
			)
			(layer "B.Fab")
		)
		(fp_line
			(start 0.12065 -0.2794)
			(end -0.12065 -0.2794)
			(stroke
				(width 0.1)
				(type default)
			)
			(layer "B.Fab")
		)
		(fp_line
			(start 0.12065 -0.305054)
			(end 0.12065 -0.2794)
			(stroke
				(width 0.1)
				(type default)
			)
			(layer "B.Fab")
		)
		(fp_line
			(start -0.120396 0.3048)
			(end -0.120396 0.2794)
			(stroke
				(width 0.1)
				(type default)
			)
			(layer "B.Fab")
		)
		(fp_line
			(start -0.120396 0.2794)
			(end 0.12065 0.2794)
			(stroke
				(width 0.1)
				(type default)
			)
			(layer "B.Fab")
		)
		(fp_line
			(start -0.12065 -0.2794)
			(end -0.12065 -0.3048)
			(stroke
				(width 0.1)
				(type default)
			)
			(layer "B.Fab")
		)
		(fp_line
			(start -0.12065 -0.3048)
			(end -0.67945 -0.3048)
			(stroke
				(width 0.1)
				(type default)
			)
			(layer "B.Fab")
		)
		(fp_line
			(start -0.67945 0.3048)
			(end -0.120396 0.3048)
			(stroke
				(width 0.1)
				(type default)
			)
			(layer "B.Fab")
		)
		(fp_line
			(start -0.67945 -0.3048)
			(end -0.67945 0.3048)
			(stroke
				(width 0.1)
				(type default)
			)
			(layer "B.Fab")
		)
		(pad "1" smd circle
			(at 0.40005 0)
			(size 0 0)
			(layers "B.Cu" "B.Mask" "B.Paste")
			(net "SMB_BIC_I2C6_MUX_FRU_R_SCL")
		)
		(pad "2" smd circle
			(at -0.40005 0)
			(size 0 0)
			(layers "B.Cu" "B.Mask" "B.Paste")
			(net "SMB_BIC_I2C6_MUX_FRU_SCL")
		)
	)
	(footprint ""
		(layer "B.Cu")
		(at 426.801788 -295.422066 180)
		(property "Reference" "C3424"
			(at 0 0 0)
			(layer "B.SilkS")
			(hide yes)
			(effects
				(font
					(size 1.27 1.27)
				)
				(justify mirror)
			)
		)
		(property "Value" ""
			(at 0 0 0)
			(layer "B.Fab")
			(effects
				(font
					(size 1.27 1.27)
				)
				(justify mirror)
			)
		)
		(duplicate_pad_numbers_are_jumpers no)
		(fp_line
			(start 1.2954 0.5842)
			(end 1.2954 -0.5842)
			(stroke
				(width 0.1524)
				(type default)
			)
			(layer "B.SilkS")
		)
		(fp_line
			(start 1.2954 -0.5842)
			(end -1.2954 -0.5842)
			(stroke
				(width 0.1524)
				(type default)
			)
			(layer "B.SilkS")
		)
		(fp_line
			(start -1.2954 0.5842)
			(end 1.2954 0.5842)
			(stroke
				(width 0.1524)
				(type default)
			)
			(layer "B.SilkS")
		)
		(fp_line
			(start -1.2954 -0.5842)
			(end -1.2954 0.5842)
			(stroke
				(width 0.1524)
				(type default)
			)
			(layer "B.SilkS")
		)
		(fp_line
			(start 1.1938 0.4064)
			(end 1.1938 -0.4064)
			(stroke
				(width 0.1)
				(type default)
			)
			(layer "B.Fab")
		)
		(fp_line
			(start 1.1938 -0.4064)
			(end 0.8636 -0.4064)
			(stroke
				(width 0.1)
				(type default)
			)
			(layer "B.Fab")
		)
		(fp_line
			(start 0.8636 0.4572)
			(end 0.8636 0.4064)
			(stroke
				(width 0.1)
				(type default)
			)
			(layer "B.Fab")
		)
		(fp_line
			(start 0.8636 0.4064)
			(end 1.1938 0.4064)
			(stroke
				(width 0.1)
				(type default)
			)
			(layer "B.Fab")
		)
		(fp_line
			(start 0.8636 -0.4064)
			(end 0.8636 -0.4572)
			(stroke
				(width 0.1)
				(type default)
			)
			(layer "B.Fab")
		)
		(fp_line
			(start 0.8636 -0.4572)
			(end -0.8636 -0.4572)
			(stroke
				(width 0.1)
				(type default)
			)
			(layer "B.Fab")
		)
		(fp_line
			(start -0.8636 0.4572)
			(end 0.8636 0.4572)
			(stroke
				(width 0.1)
				(type default)
			)
			(layer "B.Fab")
		)
		(fp_line
			(start -0.8636 0.4064)
			(end -0.8636 0.4572)
			(stroke
				(width 0.1)
				(type default)
			)
			(layer "B.Fab")
		)
		(fp_line
			(start -0.8636 -0.4064)
			(end -1.1938 -0.4064)
			(stroke
				(width 0.1)
				(type default)
			)
			(layer "B.Fab")
		)
		(fp_line
			(start -0.8636 -0.4572)
			(end -0.8636 -0.4064)
			(stroke
				(width 0.1)
				(type default)
			)
			(layer "B.Fab")
		)
		(fp_line
			(start -1.1938 0.4064)
			(end -0.8636 0.4064)
			(stroke
				(width 0.1)
				(type default)
			)
			(layer "B.Fab")
		)
		(fp_line
			(start -1.1938 -0.4064)
			(end -1.1938 0.4064)
			(stroke
				(width 0.1)
				(type default)
			)
			(layer "B.Fab")
		)
		(pad "1" smd rect
			(at 0.7366 0 90)
			(size 0.7112 0.8128)
			(layers "B.Cu" "B.Mask" "B.Paste")
			(net "P1V25_PEX3")
		)
		(pad "2" smd rect
			(at -0.7366 0 90)
			(size 0.7112 0.8128)
			(layers "B.Cu" "B.Mask" "B.Paste")
			(net "GND")
		)
	)
)
